# T6G (Grand Teton) — schematic netlist excerpt (pin names and nets, part order shuffled) for the footprints in the layout excerpt that follows; sources: Cadence DE-HDL packaged netlist, KiCad conversion of 04192023_DAF0TMB3IC0_F0TG_MB_C_brd_V02_OCP.brd

PR129  Q_RES  0 5% EMPTY  pkg 0402LF  page 207 : A = PVDD11_S3_P0_RESET_N_R ; B = PVDD11_S3_P0_RESET_N
PC369  Q_CAP  2.2UF 10V 10% X6S  pkg C0402  page 218 : A = PVDDCR_CPU1_P1_VCC1 ; B = GND

(kicad_pcb
	(version 20260206)
	(generator "pcbnew")
	(generator_version "10.0")
	(general
		(thickness 1.6)
		(legacy_teardrops no)
	)
	(paper "A4")
	(title_block
		(title "04192023_DAF0TMB3IC0_F0TG_MB_C_brd_V02_OCP.brd")
		(comment 1 "Grand Teton / footprints 2643-2644 of 8354")
	)
	(layers
		(0 "F.Cu" signal "TOP")
		(4 "In1.Cu" signal "GND")
		(6 "In2.Cu" signal "IN1")
		(8 "In3.Cu" signal "GND1")
		(10 "In4.Cu" signal "IN2")
		(12 "In5.Cu" signal "GND2")
		(14 "In6.Cu" signal "IN3")
		(16 "In7.Cu" signal "GND3")
		(18 "In8.Cu" signal "VCC")
		(20 "In9.Cu" signal "VCC1")
		(22 "In10.Cu" signal "GND4")
		(24 "In11.Cu" signal "IN4")
		(26 "In12.Cu" signal "GND5")
		(28 "In13.Cu" signal "IN5")
		(30 "In14.Cu" signal "GND6")
		(32 "In15.Cu" signal "IN6")
		(34 "In16.Cu" signal "GND7")
		(2 "B.Cu" signal "BOTTOM")
		(9 "F.Adhes" user "F.Adhesive")
		(11 "B.Adhes" user "B.Adhesive")
		(13 "F.Paste" user "Package Geometry/Pastemask Top")
		(15 "B.Paste" user "Package Geometry/Pastemask Bottom")
		(5 "F.SilkS" user "Ref Des/Silkscreen Top")
		(7 "B.SilkS" user "Ref Des/Silkscreen Bottom")
		(1 "F.Mask" user "Board Geometry/Soldermask Top")
		(3 "B.Mask" user "Board Geometry/Soldermask Bottom")
		(17 "Dwgs.User" user "User.Drawings")
		(19 "Cmts.User" user "User.Comments")
		(21 "Eco1.User" user "User.Eco1")
		(23 "Eco2.User" user "User.Eco2")
		(25 "Edge.Cuts" user "Board Geometry/Outline")
		(27 "Margin" user)
		(31 "F.CrtYd" user "Package Geometry/Place Bound Top")
		(29 "B.CrtYd" user "Package Geometry/Place Bound Bottom")
		(35 "F.Fab" user "Ref Des/Assembly Top")
		(33 "B.Fab" user "Ref Des/Assembly Bottom")
	)
	(footprint ""
		(layer "F.Cu")
		(at 414.325562 -361.814364 180)
		(property "Reference" "PR129"
			(at 0 0 180)
			(layer "F.SilkS")
			(hide yes)
			(effects
				(font
					(size 1.27 1.27)
				)
			)
		)
		(property "Value" ""
			(at 0 0 180)
			(layer "F.Fab")
			(effects
				(font
					(size 1.27 1.27)
				)
			)
		)
		(duplicate_pad_numbers_are_jumpers no)
		(fp_line
			(start 0.7874 0.4064)
			(end -0.7874 0.4064)
			(stroke
				(width 0.1524)
				(type default)
			)
			(layer "F.SilkS")
		)
		(fp_line
			(start 0.7874 -0.4064)
			(end 0.7874 0.4064)
			(stroke
				(width 0.1524)
				(type default)
			)
			(layer "F.SilkS")
		)
		(fp_line
			(start -0.7874 0.4064)
			(end -0.7874 -0.4064)
			(stroke
				(width 0.1524)
				(type default)
			)
			(layer "F.SilkS")
		)
		(fp_line
			(start -0.7874 -0.4064)
			(end 0.7874 -0.4064)
			(stroke
				(width 0.1524)
				(type default)
			)
			(layer "F.SilkS")
		)
		(fp_line
			(start 0.67945 0.3048)
			(end 0.120396 0.3048)
			(stroke
				(width 0.1)
				(type default)
			)
			(layer "F.Fab")
		)
		(fp_line
			(start 0.67945 -0.3048)
			(end 0.67945 0.3048)
			(stroke
				(width 0.1)
				(type default)
			)
			(layer "F.Fab")
		)
		(fp_line
			(start 0.12065 -0.2794)
			(end 0.12065 -0.3048)
			(stroke
				(width 0.1)
				(type default)
			)
			(layer "F.Fab")
		)
		(fp_line
			(start 0.12065 -0.3048)
			(end 0.67945 -0.3048)
			(stroke
				(width 0.1)
				(type default)
			)
			(layer "F.Fab")
		)
		(fp_line
			(start 0.120396 0.3048)
			(end 0.120396 0.2794)
			(stroke
				(width 0.1)
				(type default)
			)
			(layer "F.Fab")
		)
		(fp_line
			(start 0.120396 0.2794)
			(end -0.12065 0.2794)
			(stroke
				(width 0.1)
				(type default)
			)
			(layer "F.Fab")
		)
		(fp_line
			(start -0.12065 0.3048)
			(end -0.67945 0.3048)
			(stroke
				(width 0.1)
				(type default)
			)
			(layer "F.Fab")
		)
		(fp_line
			(start -0.12065 0.2794)
			(end -0.12065 0.3048)
			(stroke
				(width 0.1)
				(type default)
			)
			(layer "F.Fab")
		)
		(fp_line
			(start -0.12065 -0.2794)
			(end 0.12065 -0.2794)
			(stroke
				(width 0.1)
				(type default)
			)
			(layer "F.Fab")
		)
		(fp_line
			(start -0.12065 -0.305054)
			(end -0.12065 -0.2794)
			(stroke
				(width 0.1)
				(type default)
			)
			(layer "F.Fab")
		)
		(fp_line
			(start -0.67945 0.3048)
			(end -0.67945 -0.305054)
			(stroke
				(width 0.1)
				(type default)
			)
			(layer "F.Fab")
		)
		(fp_line
			(start -0.67945 -0.305054)
			(end -0.12065 -0.305054)
			(stroke
				(width 0.1)
				(type default)
			)
			(layer "F.Fab")
		)
		(pad "1" smd circle
			(at -0.40005 0 180)
			(size 0 0)
			(layers "F.Cu" "F.Mask" "F.Paste")
			(net "PVDD11_S3_P0_RESET_N_R")
		)
		(pad "2" smd circle
			(at 0.40005 0 180)
			(size 0 0)
			(layers "F.Cu" "F.Mask" "F.Paste")
			(net "PVDD11_S3_P0_RESET_N")
		)
	)
	(footprint ""
		(layer "F.Cu")
		(at 83.439254 -337.643724 90)
		(property "Reference" "PC369"
			(at 0 0 90)
			(layer "F.SilkS")
			(hide yes)
			(effects
				(font
					(size 1.27 1.27)
				)
			)
		)
		(property "Value" ""
			(at 0 0 90)
			(layer "F.Fab")
			(effects
				(font
					(size 1.27 1.27)
				)
			)
		)
		(duplicate_pad_numbers_are_jumpers no)
		(fp_line
			(start 0.7874 -0.4064)
			(end 0.7874 0.4064)
			(stroke
				(width 0.1524)
				(type default)
			)
			(layer "F.SilkS")
		)
		(fp_line
			(start -0.7874 -0.4064)
			(end 0.7874 -0.4064)
			(stroke
				(width 0.1524)
				(type default)
			)
			(layer "F.SilkS")
		)
		(fp_line
			(start 0.7874 0.4064)
			(end 0.481076 0.4064)
			(stroke
				(width 0.1524)
				(type default)
			)
			(layer "F.SilkS")
		)
		(fp_line
			(start -0.306324 0.4064)
			(end -0.7874 0.4064)
			(stroke
				(width 0.1524)
				(type default)
			)
			(layer "F.SilkS")
		)
		(fp_line
			(start -0.7874 0.4064)
			(end -0.7874 -0.4064)
			(stroke
				(width 0.1524)
				(type default)
			)
			(layer "F.SilkS")
		)
		(fp_line
			(start -0.12065 -0.305054)
			(end -0.12065 -0.2794)
			(stroke
				(width 0.1)
				(type default)
			)
			(layer "F.Fab")
		)
		(fp_line
			(start -0.67945 -0.305054)
			(end -0.12065 -0.305054)
			(stroke
				(width 0.1)
				(type default)
			)
			(layer "F.Fab")
		)
		(fp_line
			(start 0.67945 -0.3048)
			(end 0.67945 0.3048)
			(stroke
				(width 0.1)
				(type default)
			)
			(layer "F.Fab")
		)
		(fp_line
			(start 0.12065 -0.3048)
			(end 0.67945 -0.3048)
			(stroke
				(width 0.1)
				(type default)
			)
			(layer "F.Fab")
		)
		(fp_line
			(start 0.12065 -0.2794)
			(end 0.12065 -0.3048)
			(stroke
				(width 0.1)
				(type default)
			)
			(layer "F.Fab")
		)
		(fp_line
			(start -0.12065 -0.2794)
			(end 0.12065 -0.2794)
			(stroke
				(width 0.1)
				(type default)
			)
			(layer "F.Fab")
		)
		(fp_line
			(start 0.120396 0.2794)
			(end -0.12065 0.2794)
			(stroke
				(width 0.1)
				(type default)
			)
			(layer "F.Fab")
		)
		(fp_line
			(start -0.12065 0.2794)
			(end -0.12065 0.3048)
			(stroke
				(width 0.1)
				(type default)
			)
			(layer "F.Fab")
		)
		(fp_line
			(start 0.67945 0.3048)
			(end 0.120396 0.3048)
			(stroke
				(width 0.1)
				(type default)
			)
			(layer "F.Fab")
		)
		(fp_line
			(start 0.120396 0.3048)
			(end 0.120396 0.2794)
			(stroke
				(width 0.1)
				(type default)
			)
			(layer "F.Fab")
		)
		(fp_line
			(start -0.12065 0.3048)
			(end -0.67945 0.3048)
			(stroke
				(width 0.1)
				(type default)
			)
			(layer "F.Fab")
		)
		(fp_line
			(start -0.67945 0.3048)
			(end -0.67945 -0.305054)
			(stroke
				(width 0.1)
				(type default)
			)
			(layer "F.Fab")
		)
		(pad "1" smd circle
			(at -0.40005 0 90)
			(size 0 0)
			(layers "F.Cu" "F.Mask" "F.Paste")
			(net "PVDDCR_CPU1_P1_VCC1")
		)
		(pad "2" smd circle
			(at 0.40005 0 90)
			(size 0 0)
			(layers "F.Cu" "F.Mask" "F.Paste")
			(net "GND")
		)
	)
)
